# ZAIUS-MB-EVT3-HW-EBOM-X00_20161228-add_2nd_source_X15-20170106-Final.xls — Summary (bom)
| PLATFORM SOURCING AND PSL COMPLIANCE |  |  |  |  |  |  |  |  |  |
| Platform Name: |  |  |  |  |  |  |  |  |  |
| REVISION HISTORY |  |  |  |  |  |  |  |  |  |
| BOM Revision: | ECR # | Revision Description | Originator | Date |  |  |  |  |  |
| Commodity Sourcing | # of components (X00 BOM) | % of Total | # of components (X01 BOM) | % of Total | # of components (X02 BOM) | % of Total | # of components (RTS) | % of Total | Risk Mitigation Plans in Place |
| Sole Source |  |  |  |  |  |  |  |  |  |
| Single Source |  |  |  |  |  |  |  |  |  |
| Multiple |  |  |  |  |  |  |  |  | NA |
| Total |  |  |  |  |  |  |  |  | NA |
|  |  | # of components | # of components aligned with Customer PSL* | % PSL alignment |  |  |  |  |  |
| Class 1 (Customer Managed) |  |  |  |  |  |  |  |  |  |
| Class 2 (ODM Managed to Customer PSL) |  |  |  |  |  |  |  |  |  |
| All other components(ODM Managed to ODM PSL) |  |  |  |  |  |  |  |  |  |
| *RFQ and/or Contract will list requirements for complying with Customer's PSL |  |  |  |  |  |  |  |  |  |
| Reference for quotation |  |  |  |  |  |  |  |  |  |
